# SCM (Grand Teton) — schematic netlist excerpt (pin names and nets, part order shuffled) for the footprints in the layout excerpt that follows; sources: Cadence DE-HDL packaged netlist, KiCad conversion of 12092022_DA0F0TMDCD0_F0T_Management_Board_D_brd_V3_OCP.brd

R775  Q_RES  1K 1% CHIP  pkg 0402LF  page 15 : A = BATTERY_DETECT ; B = BATTERY_DETECT_R
R172  Q_RES  22 1% CHIP  pkg 0402LF  page 13 : A = RMII_TXD0_R ; B = RMII_TXD0

(kicad_pcb
	(version 20260206)
	(generator "pcbnew")
	(generator_version "10.0")
	(general
		(thickness 1.6)
		(legacy_teardrops no)
	)
	(paper "A4")
	(title_block
		(title "12092022_DA0F0TMDCD0_F0T_Management_Board_D_brd_V3_OCP.brd")
		(comment 1 "Grand Teton / footprints 992-993 of 1440")
	)
	(layers
		(0 "F.Cu" signal "TOP")
		(4 "In1.Cu" signal "GND")
		(6 "In2.Cu" signal "IN1")
		(8 "In3.Cu" signal "GND1")
		(10 "In4.Cu" signal "IN2")
		(12 "In5.Cu" signal "VCC")
		(14 "In6.Cu" signal "VCC1")
		(16 "In7.Cu" signal "IN3")
		(18 "In8.Cu" signal "GND2")
		(20 "In9.Cu" signal "IN4")
		(22 "In10.Cu" signal "GND3")
		(2 "B.Cu" signal "BOTTOM")
		(9 "F.Adhes" user "F.Adhesive")
		(11 "B.Adhes" user "B.Adhesive")
		(13 "F.Paste" user "Package Geometry/Pastemask Top")
		(15 "B.Paste" user "Package Geometry/Pastemask Bottom")
		(5 "F.SilkS" user "Ref Des/Silkscreen Top")
		(7 "B.SilkS" user "Ref Des/Silkscreen Bottom")
		(1 "F.Mask" user "Board Geometry/Soldermask Top")
		(3 "B.Mask" user "Board Geometry/Soldermask Bottom")
		(17 "Dwgs.User" user "User.Drawings")
		(19 "Cmts.User" user "User.Comments")
		(21 "Eco1.User" user "User.Eco1")
		(23 "Eco2.User" user "User.Eco2")
		(25 "Edge.Cuts" user "Board Geometry/Outline")
		(27 "Margin" user)
		(31 "F.CrtYd" user "Package Geometry/Place Bound Top")
		(29 "B.CrtYd" user "Package Geometry/Place Bound Bottom")
		(35 "F.Fab" user "Ref Des/Assembly Top")
		(33 "B.Fab" user "Ref Des/Assembly Bottom")
	)
	(footprint ""
		(layer "B.Cu")
		(at 47.850044 -74.954384)
		(property "Reference" "R775"
			(at 0 0 0)
			(layer "B.SilkS")
			(hide yes)
			(effects
				(font
					(size 1.27 1.27)
				)
				(justify mirror)
			)
		)
		(property "Value" ""
			(at 0 0 0)
			(layer "B.Fab")
			(effects
				(font
					(size 1.27 1.27)
				)
				(justify mirror)
			)
		)
		(duplicate_pad_numbers_are_jumpers no)
		(fp_line
			(start -0.7874 -0.4064)
			(end -0.7874 0.4064)
			(stroke
				(width 0.1524)
				(type default)
			)
			(layer "B.SilkS")
		)
		(fp_line
			(start -0.7874 0.4064)
			(end 0.7874 0.4064)
			(stroke
				(width 0.1524)
				(type default)
			)
			(layer "B.SilkS")
		)
		(fp_line
			(start 0.7874 -0.4064)
			(end -0.7874 -0.4064)
			(stroke
				(width 0.1524)
				(type default)
			)
			(layer "B.SilkS")
		)
		(fp_line
			(start 0.7874 0.4064)
			(end 0.7874 -0.4064)
			(stroke
				(width 0.1524)
				(type default)
			)
			(layer "B.SilkS")
		)
		(fp_line
			(start -0.67945 -0.3048)
			(end -0.67945 0.3048)
			(stroke
				(width 0.1)
				(type default)
			)
			(layer "B.Fab")
		)
		(fp_line
			(start -0.67945 0.3048)
			(end -0.120396 0.3048)
			(stroke
				(width 0.1)
				(type default)
			)
			(layer "B.Fab")
		)
		(fp_line
			(start -0.12065 -0.3048)
			(end -0.67945 -0.3048)
			(stroke
				(width 0.1)
				(type default)
			)
			(layer "B.Fab")
		)
		(fp_line
			(start -0.12065 -0.2794)
			(end -0.12065 -0.3048)
			(stroke
				(width 0.1)
				(type default)
			)
			(layer "B.Fab")
		)
		(fp_line
			(start -0.120396 0.2794)
			(end 0.12065 0.2794)
			(stroke
				(width 0.1)
				(type default)
			)
			(layer "B.Fab")
		)
		(fp_line
			(start -0.120396 0.3048)
			(end -0.120396 0.2794)
			(stroke
				(width 0.1)
				(type default)
			)
			(layer "B.Fab")
		)
		(fp_line
			(start 0.12065 -0.305054)
			(end 0.12065 -0.2794)
			(stroke
				(width 0.1)
				(type default)
			)
			(layer "B.Fab")
		)
		(fp_line
			(start 0.12065 -0.2794)
			(end -0.12065 -0.2794)
			(stroke
				(width 0.1)
				(type default)
			)
			(layer "B.Fab")
		)
		(fp_line
			(start 0.12065 0.2794)
			(end 0.12065 0.3048)
			(stroke
				(width 0.1)
				(type default)
			)
			(layer "B.Fab")
		)
		(fp_line
			(start 0.12065 0.3048)
			(end 0.67945 0.3048)
			(stroke
				(width 0.1)
				(type default)
			)
			(layer "B.Fab")
		)
		(fp_line
			(start 0.67945 -0.305054)
			(end 0.12065 -0.305054)
			(stroke
				(width 0.1)
				(type default)
			)
			(layer "B.Fab")
		)
		(fp_line
			(start 0.67945 0.3048)
			(end 0.67945 -0.305054)
			(stroke
				(width 0.1)
				(type default)
			)
			(layer "B.Fab")
		)
		(pad "1" smd circle
			(at 0.40005 0 180)
			(size 0 0)
			(layers "B.Cu" "B.Mask" "B.Paste")
			(net "BATTERY_DETECT")
		)
		(pad "2" smd circle
			(at -0.40005 0 180)
			(size 0 0)
			(layers "B.Cu" "B.Mask" "B.Paste")
			(net "BATTERY_DETECT_R")
		)
	)
	(footprint ""
		(layer "B.Cu")
		(at 41.9989 -40.9321)
		(property "Reference" "R172"
			(at 0 0 0)
			(layer "B.SilkS")
			(hide yes)
			(effects
				(font
					(size 1.27 1.27)
				)
				(justify mirror)
			)
		)
		(property "Value" ""
			(at 0 0 0)
			(layer "B.Fab")
			(effects
				(font
					(size 1.27 1.27)
				)
				(justify mirror)
			)
		)
		(duplicate_pad_numbers_are_jumpers no)
		(fp_line
			(start -0.7874 -0.4064)
			(end -0.7874 0.4064)
			(stroke
				(width 0.1524)
				(type default)
			)
			(layer "B.SilkS")
		)
		(fp_line
			(start -0.7874 0.4064)
			(end 0.7874 0.4064)
			(stroke
				(width 0.1524)
				(type default)
			)
			(layer "B.SilkS")
		)
		(fp_line
			(start 0.7874 -0.4064)
			(end -0.7874 -0.4064)
			(stroke
				(width 0.1524)
				(type default)
			)
			(layer "B.SilkS")
		)
		(fp_line
			(start 0.7874 0.4064)
			(end 0.7874 -0.4064)
			(stroke
				(width 0.1524)
				(type default)
			)
			(layer "B.SilkS")
		)
		(fp_line
			(start -0.67945 -0.3048)
			(end -0.67945 0.3048)
			(stroke
				(width 0.1)
				(type default)
			)
			(layer "B.Fab")
		)
		(fp_line
			(start -0.67945 0.3048)
			(end -0.120396 0.3048)
			(stroke
				(width 0.1)
				(type default)
			)
			(layer "B.Fab")
		)
		(fp_line
			(start -0.12065 -0.3048)
			(end -0.67945 -0.3048)
			(stroke
				(width 0.1)
				(type default)
			)
			(layer "B.Fab")
		)
		(fp_line
			(start -0.12065 -0.2794)
			(end -0.12065 -0.3048)
			(stroke
				(width 0.1)
				(type default)
			)
			(layer "B.Fab")
		)
		(fp_line
			(start -0.120396 0.2794)
			(end 0.12065 0.2794)
			(stroke
				(width 0.1)
				(type default)
			)
			(layer "B.Fab")
		)
		(fp_line
			(start -0.120396 0.3048)
			(end -0.120396 0.2794)
			(stroke
				(width 0.1)
				(type default)
			)
			(layer "B.Fab")
		)
		(fp_line
			(start 0.12065 -0.305054)
			(end 0.12065 -0.2794)
			(stroke
				(width 0.1)
				(type default)
			)
			(layer "B.Fab")
		)
		(fp_line
			(start 0.12065 -0.2794)
			(end -0.12065 -0.2794)
			(stroke
				(width 0.1)
				(type default)
			)
			(layer "B.Fab")
		)
		(fp_line
			(start 0.12065 0.2794)
			(end 0.12065 0.3048)
			(stroke
				(width 0.1)
				(type default)
			)
			(layer "B.Fab")
		)
		(fp_line
			(start 0.12065 0.3048)
			(end 0.67945 0.3048)
			(stroke
				(width 0.1)
				(type default)
			)
			(layer "B.Fab")
		)
		(fp_line
			(start 0.67945 -0.305054)
			(end 0.12065 -0.305054)
			(stroke
				(width 0.1)
				(type default)
			)
			(layer "B.Fab")
		)
		(fp_line
			(start 0.67945 0.3048)
			(end 0.67945 -0.305054)
			(stroke
				(width 0.1)
				(type default)
			)
			(layer "B.Fab")
		)
		(pad "1" smd circle
			(at 0.40005 0 180)
			(size 0 0)
			(layers "B.Cu" "B.Mask" "B.Paste")
			(net "RMII_TXD0_R")
		)
		(pad "2" smd circle
			(at -0.40005 0 180)
			(size 0 0)
			(layers "B.Cu" "B.Mask" "B.Paste")
			(net "RMII_TXD0")
		)
	)
)
